# S9S_MB_2U (Grand Teton) — schematic netlist excerpt (pin names and nets, part order shuffled) for the footprints in the layout excerpt that follows; sources: Cadence DE-HDL packaged netlist, KiCad conversion of 03242023_DA0F0TMBIJ0_F0T_Motherboard_J_brd_V01_OCP.brd

R4132  Q_RES  100K 1% EMPTY  pkg 0402LF  page 146 : A = GPU_3V3IO_RSVD3_FFU ; B = GND
R188  Q_RES  0 5% CHIP  pkg 0402LF  page 123 : A = H_CPU_NMI_LVC1_R_N ; B = H_CPU_NMI_LVC1_N

(kicad_pcb
	(version 20260206)
	(generator "pcbnew")
	(generator_version "10.0")
	(general
		(thickness 1.6)
		(legacy_teardrops no)
	)
	(paper "A4")
	(title_block
		(title "03242023_DA0F0TMBIJ0_F0T_Motherboard_J_brd_V01_OCP.brd")
		(comment 1 "Grand Teton / footprints 506-507 of 6105")
	)
	(layers
		(0 "F.Cu" signal "TOP")
		(4 "In1.Cu" signal "GND")
		(6 "In2.Cu" signal "IN1")
		(8 "In3.Cu" signal "GND1")
		(10 "In4.Cu" signal "IN2")
		(12 "In5.Cu" signal "GND2")
		(14 "In6.Cu" signal "IN3")
		(16 "In7.Cu" signal "GND3")
		(18 "In8.Cu" signal "VCC")
		(20 "In9.Cu" signal "VCC1")
		(22 "In10.Cu" signal "GND4")
		(24 "In11.Cu" signal "IN4")
		(26 "In12.Cu" signal "GND5")
		(28 "In13.Cu" signal "IN5")
		(30 "In14.Cu" signal "GND6")
		(32 "In15.Cu" signal "IN6")
		(34 "In16.Cu" signal "GND7")
		(2 "B.Cu" signal "BOTTOM")
		(9 "F.Adhes" user "F.Adhesive")
		(11 "B.Adhes" user "B.Adhesive")
		(13 "F.Paste" user "Package Geometry/Pastemask Top")
		(15 "B.Paste" user "Package Geometry/Pastemask Bottom")
		(5 "F.SilkS" user "Ref Des/Silkscreen Top")
		(7 "B.SilkS" user "Ref Des/Silkscreen Bottom")
		(1 "F.Mask" user "Board Geometry/Soldermask Top")
		(3 "B.Mask" user "Board Geometry/Soldermask Bottom")
		(17 "Dwgs.User" user "User.Drawings")
		(19 "Cmts.User" user "User.Comments")
		(21 "Eco1.User" user "User.Eco1")
		(23 "Eco2.User" user "User.Eco2")
		(25 "Edge.Cuts" user "Board Geometry/Outline")
		(27 "Margin" user)
		(31 "F.CrtYd" user "Package Geometry/Place Bound Top")
		(29 "B.CrtYd" user "Package Geometry/Place Bound Bottom")
		(35 "F.Fab" user "Ref Des/Assembly Top")
		(33 "B.Fab" user "Ref Des/Assembly Bottom")
	)
	(footprint ""
		(layer "F.Cu")
		(at 302.85436 -430.65827 -90)
		(property "Reference" "R4132"
			(at 0 0 270)
			(layer "F.SilkS")
			(hide yes)
			(effects
				(font
					(size 1.27 1.27)
				)
			)
		)
		(property "Value" ""
			(at 0 0 270)
			(layer "F.Fab")
			(effects
				(font
					(size 1.27 1.27)
				)
			)
		)
		(duplicate_pad_numbers_are_jumpers no)
		(fp_line
			(start -0.7874 0.4064)
			(end -0.7874 -0.4064)
			(stroke
				(width 0.1524)
				(type default)
			)
			(layer "F.SilkS")
		)
		(fp_line
			(start 0.7874 0.4064)
			(end -0.7874 0.4064)
			(stroke
				(width 0.1524)
				(type default)
			)
			(layer "F.SilkS")
		)
		(fp_line
			(start -0.7874 -0.4064)
			(end 0.7874 -0.4064)
			(stroke
				(width 0.1524)
				(type default)
			)
			(layer "F.SilkS")
		)
		(fp_line
			(start 0.7874 -0.4064)
			(end 0.7874 0.4064)
			(stroke
				(width 0.1524)
				(type default)
			)
			(layer "F.SilkS")
		)
		(fp_line
			(start -0.67945 0.3048)
			(end -0.67945 -0.305054)
			(stroke
				(width 0.1)
				(type default)
			)
			(layer "F.Fab")
		)
		(fp_line
			(start -0.12065 0.3048)
			(end -0.67945 0.3048)
			(stroke
				(width 0.1)
				(type default)
			)
			(layer "F.Fab")
		)
		(fp_line
			(start 0.120396 0.3048)
			(end 0.120396 0.2794)
			(stroke
				(width 0.1)
				(type default)
			)
			(layer "F.Fab")
		)
		(fp_line
			(start 0.67945 0.3048)
			(end 0.120396 0.3048)
			(stroke
				(width 0.1)
				(type default)
			)
			(layer "F.Fab")
		)
		(fp_line
			(start -0.12065 0.2794)
			(end -0.12065 0.3048)
			(stroke
				(width 0.1)
				(type default)
			)
			(layer "F.Fab")
		)
		(fp_line
			(start 0.120396 0.2794)
			(end -0.12065 0.2794)
			(stroke
				(width 0.1)
				(type default)
			)
			(layer "F.Fab")
		)
		(fp_line
			(start -0.12065 -0.2794)
			(end 0.12065 -0.2794)
			(stroke
				(width 0.1)
				(type default)
			)
			(layer "F.Fab")
		)
		(fp_line
			(start 0.12065 -0.2794)
			(end 0.12065 -0.3048)
			(stroke
				(width 0.1)
				(type default)
			)
			(layer "F.Fab")
		)
		(fp_line
			(start 0.12065 -0.3048)
			(end 0.67945 -0.3048)
			(stroke
				(width 0.1)
				(type default)
			)
			(layer "F.Fab")
		)
		(fp_line
			(start 0.67945 -0.3048)
			(end 0.67945 0.3048)
			(stroke
				(width 0.1)
				(type default)
			)
			(layer "F.Fab")
		)
		(fp_line
			(start -0.67945 -0.305054)
			(end -0.12065 -0.305054)
			(stroke
				(width 0.1)
				(type default)
			)
			(layer "F.Fab")
		)
		(fp_line
			(start -0.12065 -0.305054)
			(end -0.12065 -0.2794)
			(stroke
				(width 0.1)
				(type default)
			)
			(layer "F.Fab")
		)
		(pad "1" smd circle
			(at -0.40005 0 270)
			(size 0 0)
			(layers "F.Cu" "F.Mask" "F.Paste")
			(net "GPU_3V3IO_RSVD3_FFU")
		)
		(pad "2" smd circle
			(at 0.40005 0 270)
			(size 0 0)
			(layers "F.Cu" "F.Mask" "F.Paste")
			(net "GND")
		)
	)
	(footprint ""
		(layer "F.Cu")
		(at 187.50788 -99.659948 -90)
		(property "Reference" "R188"
			(at 0 0 270)
			(layer "F.SilkS")
			(hide yes)
			(effects
				(font
					(size 1.27 1.27)
				)
			)
		)
		(property "Value" ""
			(at 0 0 270)
			(layer "F.Fab")
			(effects
				(font
					(size 1.27 1.27)
				)
			)
		)
		(duplicate_pad_numbers_are_jumpers no)
		(fp_line
			(start -0.7874 0.4064)
			(end -0.7874 -0.4064)
			(stroke
				(width 0.1524)
				(type default)
			)
			(layer "F.SilkS")
		)
		(fp_line
			(start 0.7874 0.4064)
			(end -0.7874 0.4064)
			(stroke
				(width 0.1524)
				(type default)
			)
			(layer "F.SilkS")
		)
		(fp_line
			(start -0.7874 -0.4064)
			(end 0.7874 -0.4064)
			(stroke
				(width 0.1524)
				(type default)
			)
			(layer "F.SilkS")
		)
		(fp_line
			(start 0.7874 -0.4064)
			(end 0.7874 0.4064)
			(stroke
				(width 0.1524)
				(type default)
			)
			(layer "F.SilkS")
		)
		(fp_line
			(start -0.67945 0.3048)
			(end -0.67945 -0.305054)
			(stroke
				(width 0.1)
				(type default)
			)
			(layer "F.Fab")
		)
		(fp_line
			(start -0.12065 0.3048)
			(end -0.67945 0.3048)
			(stroke
				(width 0.1)
				(type default)
			)
			(layer "F.Fab")
		)
		(fp_line
			(start 0.120396 0.3048)
			(end 0.120396 0.2794)
			(stroke
				(width 0.1)
				(type default)
			)
			(layer "F.Fab")
		)
		(fp_line
			(start 0.67945 0.3048)
			(end 0.120396 0.3048)
			(stroke
				(width 0.1)
				(type default)
			)
			(layer "F.Fab")
		)
		(fp_line
			(start -0.12065 0.2794)
			(end -0.12065 0.3048)
			(stroke
				(width 0.1)
				(type default)
			)
			(layer "F.Fab")
		)
		(fp_line
			(start 0.120396 0.2794)
			(end -0.12065 0.2794)
			(stroke
				(width 0.1)
				(type default)
			)
			(layer "F.Fab")
		)
		(fp_line
			(start -0.12065 -0.2794)
			(end 0.12065 -0.2794)
			(stroke
				(width 0.1)
				(type default)
			)
			(layer "F.Fab")
		)
		(fp_line
			(start 0.12065 -0.2794)
			(end 0.12065 -0.3048)
			(stroke
				(width 0.1)
				(type default)
			)
			(layer "F.Fab")
		)
		(fp_line
			(start 0.12065 -0.3048)
			(end 0.67945 -0.3048)
			(stroke
				(width 0.1)
				(type default)
			)
			(layer "F.Fab")
		)
		(fp_line
			(start 0.67945 -0.3048)
			(end 0.67945 0.3048)
			(stroke
				(width 0.1)
				(type default)
			)
			(layer "F.Fab")
		)
		(fp_line
			(start -0.67945 -0.305054)
			(end -0.12065 -0.305054)
			(stroke
				(width 0.1)
				(type default)
			)
			(layer "F.Fab")
		)
		(fp_line
			(start -0.12065 -0.305054)
			(end -0.12065 -0.2794)
			(stroke
				(width 0.1)
				(type default)
			)
			(layer "F.Fab")
		)
		(pad "1" smd circle
			(at -0.40005 0 270)
			(size 0 0)
			(layers "F.Cu" "F.Mask" "F.Paste")
			(net "H_CPU_NMI_LVC1_R_N")
		)
		(pad "2" smd circle
			(at 0.40005 0 270)
			(size 0 0)
			(layers "F.Cu" "F.Mask" "F.Paste")
			(net "H_CPU_NMI_LVC1_N")
		)
	)
)
